(kicad_pcb
	(version 20260206)
	(generator "pcbnew")
	(generator_version "10.0")
	(general
		(thickness 1.6)
		(legacy_teardrops no)
	)
	(paper "A4")
	(title_block
		(title "Bryce Canyon_IOM_IOC_16318-2_OCP.brd")
		(comment 1 "Bryce Canyon / footprints 196-201 of 1605")
	)
	(layers
		(0 "F.Cu" signal "TOP")
		(4 "In1.Cu" signal "L2GND")
		(6 "In2.Cu" signal "L3")
		(8 "In3.Cu" signal "L4VCC")
		(10 "In4.Cu" signal "L5VCC")
		(12 "In5.Cu" signal "L6")
		(14 "In6.Cu" signal "L7GND")
		(2 "B.Cu" signal "BOTTOM")
		(9 "F.Adhes" user "F.Adhesive")
		(11 "B.Adhes" user "B.Adhesive")
		(13 "F.Paste" user "Package Geometry/Pastemask Top")
		(15 "B.Paste" user "Package Geometry/Pastemask Bottom")
		(5 "F.SilkS" user "Ref Des/Silkscreen Top")
		(7 "B.SilkS" user "Ref Des/Silkscreen Bottom")
		(1 "F.Mask" user "Board Geometry/Soldermask Top")
		(3 "B.Mask" user "Board Geometry/Soldermask Bottom")
		(17 "Dwgs.User" user "User.Drawings")
		(19 "Cmts.User" user "User.Comments")
		(21 "Eco1.User" user "User.Eco1")
		(23 "Eco2.User" user "User.Eco2")
		(25 "Edge.Cuts" user "Board Geometry/Outline")
		(27 "Margin" user)
		(31 "F.CrtYd" user "Package Geometry/Place Bound Top")
		(29 "B.CrtYd" user "Package Geometry/Place Bound Bottom")
		(35 "F.Fab" user "Ref Des/Assembly Top")
		(33 "B.Fab" user "Ref Des/Assembly Bottom")
	)
	(footprint ""
		(layer "F.Cu")
		(at 51.7271 -161.2519)
		(property "Reference" "C85"
			(at 0 0 0)
			(layer "F.SilkS")
			(hide yes)
			(effects
				(font
					(size 1.27 1.27)
				)
			)
		)
		(property "Value" "SCD1U16V2KX-3GP"
			(at 1.1811 -2.7051 0)
			(unlocked yes)
			(layer "F.Fab")
			(hide yes)
			(effects
				(font
					(size 1.016 1.016)
					(thickness 0.1524)
				)
			)
		)
		(property "Device Type" "C402H22"
			(at 1.1811 -4.2291 0)
			(unlocked yes)
			(layer "F.Fab")
			(hide yes)
			(effects
				(font
					(size 1.016 1.016)
					(thickness 0.1524)
				)
			)
		)
		(duplicate_pad_numbers_are_jumpers no)
		(fp_rect
			(start -0.4318 0.9525)
			(end 0.4318 -0.9525)
			(stroke
				(width 0)
				(type default)
			)
			(fill no)
			(layer "F.CrtYd")
		)
		(fp_rect
			(start -0.4318 0.9525)
			(end 0.4318 -0.9525)
			(stroke
				(width 0)
				(type default)
			)
			(fill no)
			(layer "F.Fab")
		)
		(pad "1" smd custom
			(at 0 -0.4445)
			(size 0.1524 0.1524)
			(layers "F.Cu" "F.Mask" "F.Paste")
			(net "GND")
			(options
				(clearance outline)
				(anchor circle)
			)
			(primitives
				(gr_poly
					(pts
						(arc
							(start 0.3048 -0.2032)
							(mid 0.275042 -0.275042)
							(end 0.2032 -0.3048)
						)
						(arc
							(start -0.2032 -0.3048)
							(mid -0.275042 -0.275042)
							(end -0.3048 -0.2032)
						)
						(arc
							(start -0.3048 0.2032)
							(mid -0.275042 0.275042)
							(end -0.2032 0.3048)
						)
						(arc
							(start 0.2032 0.3048)
							(mid 0.275042 0.275042)
							(end 0.3048 0.2032)
						)
					)
					(width 0)
					(fill yes)
				)
			)
		)
		(pad "2" smd custom
			(at 0 0.4445)
			(size 0.1524 0.1524)
			(layers "F.Cu" "F.Mask" "F.Paste")
			(net "ADCVREFFN")
			(options
				(clearance outline)
				(anchor circle)
			)
			(primitives
				(gr_poly
					(pts
						(arc
							(start 0.3048 -0.2032)
							(mid 0.275042 -0.275042)
							(end 0.2032 -0.3048)
						)
						(arc
							(start -0.2032 -0.3048)
							(mid -0.275042 -0.275042)
							(end -0.3048 -0.2032)
						)
						(arc
							(start -0.3048 0.2032)
							(mid -0.275042 0.275042)
							(end -0.2032 0.3048)
						)
						(arc
							(start 0.2032 0.3048)
							(mid 0.275042 0.275042)
							(end 0.3048 0.2032)
						)
					)
					(width 0)
					(fill yes)
				)
			)
		)
	)
	(footprint ""
		(layer "F.Cu")
		(at 35.394646 -174.67961 -90)
		(property "Reference" "R499"
			(at 0 0 270)
			(layer "F.SilkS")
			(hide yes)
			(effects
				(font
					(size 1.27 1.27)
				)
			)
		)
		(property "Value" "10KR2F-2-GP"
			(at 0.064008 -3.993896 270)
			(unlocked yes)
			(layer "F.Fab")
			(hide yes)
			(effects
				(font
					(size 1.016 1.016)
					(thickness 0.1524)
				)
			)
		)
		(property "Device Type" "R402H16"
			(at 0.064008 -5.517896 270)
			(unlocked yes)
			(layer "F.Fab")
			(hide yes)
			(effects
				(font
					(size 1.016 1.016)
					(thickness 0.1524)
				)
			)
		)
		(duplicate_pad_numbers_are_jumpers no)
		(fp_line
			(start -0.508 -0.9398)
			(end -0.508 0.9398)
			(stroke
				(width 0.1524)
				(type default)
			)
			(layer "F.SilkS")
		)
		(fp_line
			(start 0.508 -0.9398)
			(end -0.508 -0.9398)
			(stroke
				(width 0.1524)
				(type default)
			)
			(layer "F.SilkS")
		)
		(fp_rect
			(start -0.508 0.9398)
			(end 0.508 -0.9398)
			(stroke
				(width 0)
				(type default)
			)
			(fill no)
			(layer "F.CrtYd")
		)
		(fp_rect
			(start -0.508 0.9398)
			(end 0.508 -0.9398)
			(stroke
				(width 0)
				(type default)
			)
			(fill no)
			(layer "F.Fab")
		)
		(pad "1" smd custom
			(at 0 -0.4445 270)
			(size 0.1397 0.1397)
			(layers "F.Cu" "F.Mask" "F.Paste")
			(net "P3V3_STBY_VFB")
			(options
				(clearance outline)
				(anchor circle)
			)
			(primitives
				(gr_poly
					(pts
						(arc
							(start -0.1778 -0.2794)
							(mid -0.249642 -0.249642)
							(end -0.2794 -0.1778)
						)
						(arc
							(start -0.2794 0.1778)
							(mid -0.249642 0.249642)
							(end -0.1778 0.2794)
						)
						(arc
							(start 0.1778 0.2794)
							(mid 0.249642 0.249642)
							(end 0.2794 0.1778)
						)
						(arc
							(start 0.2794 -0.1778)
							(mid 0.249642 -0.249642)
							(end 0.1778 -0.2794)
						)
					)
					(width 0)
					(fill yes)
				)
			)
		)
		(pad "2" smd custom
			(at 0 0.4445 270)
			(size 0.1397 0.1397)
			(layers "F.Cu" "F.Mask" "F.Paste")
			(net "AGND_P3V3_STBY")
			(options
				(clearance outline)
				(anchor circle)
			)
			(primitives
				(gr_poly
					(pts
						(arc
							(start -0.1778 -0.2794)
							(mid -0.249642 -0.249642)
							(end -0.2794 -0.1778)
						)
						(arc
							(start -0.2794 0.1778)
							(mid -0.249642 0.249642)
							(end -0.1778 0.2794)
						)
						(arc
							(start 0.1778 0.2794)
							(mid 0.249642 0.249642)
							(end 0.2794 0.1778)
						)
						(arc
							(start 0.2794 -0.1778)
							(mid 0.249642 -0.249642)
							(end 0.1778 -0.2794)
						)
					)
					(width 0)
					(fill yes)
				)
			)
		)
	)
	(footprint ""
		(layer "F.Cu")
		(at 65.169796 -140.223494 90)
		(property "Reference" "R186"
			(at 0 0 90)
			(layer "F.SilkS")
			(hide yes)
			(effects
				(font
					(size 1.27 1.27)
				)
			)
		)
		(property "Value" "2K2R2F-GP"
			(at 0.064008 -3.993896 90)
			(unlocked yes)
			(layer "F.Fab")
			(hide yes)
			(effects
				(font
					(size 1.016 1.016)
					(thickness 0.1524)
				)
			)
		)
		(property "Device Type" "R402H16"
			(at 0.064008 -5.517896 90)
			(unlocked yes)
			(layer "F.Fab")
			(hide yes)
			(effects
				(font
					(size 1.016 1.016)
					(thickness 0.1524)
				)
			)
		)
		(duplicate_pad_numbers_are_jumpers no)
		(fp_line
			(start 0.508 -0.9398)
			(end -0.508 -0.9398)
			(stroke
				(width 0.1524)
				(type default)
			)
			(layer "F.SilkS")
		)
		(fp_line
			(start -0.508 -0.9398)
			(end -0.508 0.9398)
			(stroke
				(width 0.1524)
				(type default)
			)
			(layer "F.SilkS")
		)
		(fp_rect
			(start -0.508 0.9398)
			(end 0.508 -0.9398)
			(stroke
				(width 0)
				(type default)
			)
			(fill no)
			(layer "F.CrtYd")
		)
		(fp_rect
			(start -0.508 0.9398)
			(end 0.508 -0.9398)
			(stroke
				(width 0)
				(type default)
			)
			(fill no)
			(layer "F.Fab")
		)
		(pad "1" smd custom
			(at 0 -0.4445 90)
			(size 0.1397 0.1397)
			(layers "F.Cu" "F.Mask" "F.Paste")
			(net "I2C_M2_2_SDA")
			(options
				(clearance outline)
				(anchor circle)
			)
			(primitives
				(gr_poly
					(pts
						(arc
							(start -0.1778 -0.2794)
							(mid -0.249642 -0.249642)
							(end -0.2794 -0.1778)
						)
						(arc
							(start -0.2794 0.1778)
							(mid -0.249642 0.249642)
							(end -0.1778 0.2794)
						)
						(arc
							(start 0.1778 0.2794)
							(mid 0.249642 0.249642)
							(end 0.2794 0.1778)
						)
						(arc
							(start 0.2794 -0.1778)
							(mid 0.249642 -0.249642)
							(end 0.1778 -0.2794)
						)
					)
					(width 0)
					(fill yes)
				)
			)
		)
		(pad "2" smd custom
			(at 0 0.4445 90)
			(size 0.1397 0.1397)
			(layers "F.Cu" "F.Mask" "F.Paste")
			(net "P3V3_STBY")
			(options
				(clearance outline)
				(anchor circle)
			)
			(primitives
				(gr_poly
					(pts
						(arc
							(start -0.1778 -0.2794)
							(mid -0.249642 -0.249642)
							(end -0.2794 -0.1778)
						)
						(arc
							(start -0.2794 0.1778)
							(mid -0.249642 0.249642)
							(end -0.1778 0.2794)
						)
						(arc
							(start 0.1778 0.2794)
							(mid 0.249642 0.249642)
							(end 0.2794 0.1778)
						)
						(arc
							(start 0.2794 -0.1778)
							(mid 0.249642 -0.249642)
							(end 0.1778 -0.2794)
						)
					)
					(width 0)
					(fill yes)
				)
			)
		)
	)
	(footprint ""
		(layer "F.Cu")
		(at 176.6824 -58.0136 90)
		(property "Reference" "R663"
			(at 0 0 90)
			(layer "F.SilkS")
			(hide yes)
			(effects
				(font
					(size 1.27 1.27)
				)
			)
		)
		(property "Value" "10KR2F-2-GP"
			(at 0.064008 -3.993896 90)
			(unlocked yes)
			(layer "F.Fab")
			(hide yes)
			(effects
				(font
					(size 1.016 1.016)
					(thickness 0.1524)
				)
			)
		)
		(property "Device Type" "R402H16"
			(at 0.064008 -5.517896 90)
			(unlocked yes)
			(layer "F.Fab")
			(hide yes)
			(effects
				(font
					(size 1.016 1.016)
					(thickness 0.1524)
				)
			)
		)
		(duplicate_pad_numbers_are_jumpers no)
		(fp_line
			(start 0.508 -0.9398)
			(end -0.508 -0.9398)
			(stroke
				(width 0.1524)
				(type default)
			)
			(layer "F.SilkS")
		)
		(fp_line
			(start -0.508 -0.9398)
			(end -0.508 0.9398)
			(stroke
				(width 0.1524)
				(type default)
			)
			(layer "F.SilkS")
		)
		(fp_rect
			(start -0.508 0.9398)
			(end 0.508 -0.9398)
			(stroke
				(width 0)
				(type default)
			)
			(fill no)
			(layer "F.CrtYd")
		)
		(fp_rect
			(start -0.508 0.9398)
			(end 0.508 -0.9398)
			(stroke
				(width 0)
				(type default)
			)
			(fill no)
			(layer "F.Fab")
		)
		(pad "1" smd custom
			(at 0 -0.4445 90)
			(size 0.1397 0.1397)
			(layers "F.Cu" "F.Mask" "F.Paste")
			(net "P1V8")
			(options
				(clearance outline)
				(anchor circle)
			)
			(primitives
				(gr_poly
					(pts
						(arc
							(start -0.1778 -0.2794)
							(mid -0.249642 -0.249642)
							(end -0.2794 -0.1778)
						)
						(arc
							(start -0.2794 0.1778)
							(mid -0.249642 0.249642)
							(end -0.1778 0.2794)
						)
						(arc
							(start 0.1778 0.2794)
							(mid 0.249642 0.249642)
							(end 0.2794 0.1778)
						)
						(arc
							(start 0.2794 -0.1778)
							(mid 0.249642 -0.249642)
							(end 0.1778 -0.2794)
						)
					)
					(width 0)
					(fill yes)
				)
			)
		)
		(pad "2" smd custom
			(at 0 0.4445 90)
			(size 0.1397 0.1397)
			(layers "F.Cu" "F.Mask" "F.Paste")
			(net "XM_ADDR_22")
			(options
				(clearance outline)
				(anchor circle)
			)
			(primitives
				(gr_poly
					(pts
						(arc
							(start -0.1778 -0.2794)
							(mid -0.249642 -0.249642)
							(end -0.2794 -0.1778)
						)
						(arc
							(start -0.2794 0.1778)
							(mid -0.249642 0.249642)
							(end -0.1778 0.2794)
						)
						(arc
							(start 0.1778 0.2794)
							(mid 0.249642 0.249642)
							(end 0.2794 0.1778)
						)
						(arc
							(start 0.2794 -0.1778)
							(mid 0.249642 -0.249642)
							(end 0.1778 -0.2794)
						)
					)
					(width 0)
					(fill yes)
				)
			)
		)
	)
	(footprint ""
		(layer "F.Cu")
		(at 224.932748 -78.93177)
		(property "Reference" "LED4"
			(at 0 0 0)
			(layer "F.SilkS")
			(hide yes)
			(effects
				(font
					(size 1.27 1.27)
				)
			)
		)
		(property "Value" "LED-YG-51-GP"
			(at -2.6924 -1.4224 0)
			(unlocked yes)
			(layer "F.Fab")
			(hide yes)
			(effects
				(font
					(size 1.016 1.016)
					(thickness 0.1524)
				)
			)
		)
		(property "Device Type" "LED1608AKH40"
			(at -2.6924 -2.9464 0)
			(unlocked yes)
			(layer "F.Fab")
			(hide yes)
			(effects
				(font
					(size 1.016 1.016)
					(thickness 0.1524)
				)
			)
		)
		(duplicate_pad_numbers_are_jumpers no)
		(fp_line
			(start -0.7493 1.651)
			(end -0.7493 1.1811)
			(stroke
				(width 0.3302)
				(type default)
			)
			(layer "F.SilkS")
		)
		(fp_line
			(start -0.6604 -1.3716)
			(end 0.6604 -1.3716)
			(stroke
				(width 0.1524)
				(type default)
			)
			(layer "F.SilkS")
		)
		(fp_line
			(start -0.6604 1.3716)
			(end -0.6604 -1.3716)
			(stroke
				(width 0.1524)
				(type default)
			)
			(layer "F.SilkS")
		)
		(fp_line
			(start -0.5969 1.5494)
			(end 0.5842 1.5494)
			(stroke
				(width 0.508)
				(type default)
			)
			(layer "F.SilkS")
		)
		(fp_line
			(start 0.6604 -1.3716)
			(end 0.6604 1.3716)
			(stroke
				(width 0.1524)
				(type default)
			)
			(layer "F.SilkS")
		)
		(fp_line
			(start 0.6604 1.3716)
			(end -0.6604 1.3716)
			(stroke
				(width 0.1524)
				(type default)
			)
			(layer "F.SilkS")
		)
		(fp_line
			(start 0.7493 1.651)
			(end 0.7493 1.1811)
			(stroke
				(width 0.3302)
				(type default)
			)
			(layer "F.SilkS")
		)
		(fp_rect
			(start -0.6223 1.3335)
			(end 0.6223 -1.3335)
			(stroke
				(width 0)
				(type default)
			)
			(fill no)
			(layer "F.CrtYd")
		)
		(fp_rect
			(start -0.6223 1.3335)
			(end 0.6223 -1.3335)
			(stroke
				(width 0)
				(type default)
			)
			(fill no)
			(layer "F.Fab")
		)
		(pad "A" smd custom
			(at 0 -0.762)
			(size 0.2159 0.2159)
			(layers "F.Cu" "F.Mask" "F.Paste")
			(net "SYS_ERROR_LED_R")
			(options
				(clearance outline)
				(anchor circle)
			)
			(primitives
				(gr_poly
					(pts
						(arc
							(start -0.3302 -0.4318)
							(mid -0.402042 -0.402042)
							(end -0.4318 -0.3302)
						)
						(arc
							(start -0.4318 0.3302)
							(mid -0.402042 0.402042)
							(end -0.3302 0.4318)
						)
						(arc
							(start 0.3302 0.4318)
							(mid 0.402042 0.402042)
							(end 0.4318 0.3302)
						)
						(arc
							(start 0.4318 -0.3302)
							(mid 0.402042 -0.402042)
							(end 0.3302 -0.4318)
						)
					)
					(width 0)
					(fill yes)
				)
			)
		)
		(pad "K" smd custom
			(at 0 0.762)
			(size 0.2159 0.2159)
			(layers "F.Cu" "F.Mask" "F.Paste")
			(net "SYS_ERROR_LED_D")
			(options
				(clearance outline)
				(anchor circle)
			)
			(primitives
				(gr_poly
					(pts
						(arc
							(start -0.3302 -0.4318)
							(mid -0.402042 -0.402042)
							(end -0.4318 -0.3302)
						)
						(arc
							(start -0.4318 0.3302)
							(mid -0.402042 0.402042)
							(end -0.3302 0.4318)
						)
						(arc
							(start 0.3302 0.4318)
							(mid 0.402042 0.402042)
							(end 0.4318 0.3302)
						)
						(arc
							(start 0.4318 -0.3302)
							(mid 0.402042 -0.402042)
							(end 0.3302 -0.4318)
						)
					)
					(width 0)
					(fill yes)
				)
			)
		)
	)
	(footprint ""
		(layer "F.Cu")
		(at 93.609668 -57.133236 90)
		(property "Reference" "R719"
			(at 0 0 90)
			(layer "F.SilkS")
			(hide yes)
			(effects
				(font
					(size 1.27 1.27)
				)
			)
		)
		(property "Value" "0R2J-2-GP"
			(at 0.064008 -3.993896 90)
			(unlocked yes)
			(layer "F.Fab")
			(hide yes)
			(effects
				(font
					(size 1.016 1.016)
					(thickness 0.1524)
				)
			)
		)
		(property "Device Type" "R402H16"
			(at 0.064008 -5.517896 90)
			(unlocked yes)
			(layer "F.Fab")
			(hide yes)
			(effects
				(font
					(size 1.016 1.016)
					(thickness 0.1524)
				)
			)
		)
		(duplicate_pad_numbers_are_jumpers no)
		(fp_line
			(start 0.508 -0.9398)
			(end -0.508 -0.9398)
			(stroke
				(width 0.1524)
				(type default)
			)
			(layer "F.SilkS")
		)
		(fp_line
			(start -0.508 -0.9398)
			(end -0.508 0.9398)
			(stroke
				(width 0.1524)
				(type default)
			)
			(layer "F.SilkS")
		)
		(fp_rect
			(start -0.508 0.9398)
			(end 0.508 -0.9398)
			(stroke
				(width 0)
				(type default)
			)
			(fill no)
			(layer "F.CrtYd")
		)
		(fp_rect
			(start -0.508 0.9398)
			(end 0.508 -0.9398)
			(stroke
				(width 0)
				(type default)
			)
			(fill no)
			(layer "F.Fab")
		)
		(pad "1" smd custom
			(at 0 -0.4445 90)
			(size 0.1397 0.1397)
			(layers "F.Cu" "F.Mask" "F.Paste")
			(net "P3V3_EN_R")
			(options
				(clearance outline)
				(anchor circle)
			)
			(primitives
				(gr_poly
					(pts
						(arc
							(start -0.1778 -0.2794)
							(mid -0.249642 -0.249642)
							(end -0.2794 -0.1778)
						)
						(arc
							(start -0.2794 0.1778)
							(mid -0.249642 0.249642)
							(end -0.1778 0.2794)
						)
						(arc
							(start 0.1778 0.2794)
							(mid 0.249642 0.249642)
							(end 0.2794 0.1778)
						)
						(arc
							(start 0.2794 -0.1778)
							(mid 0.249642 -0.249642)
							(end 0.1778 -0.2794)
						)
					)
					(width 0)
					(fill yes)
				)
			)
		)
		(pad "2" smd custom
			(at 0 0.4445 90)
			(size 0.1397 0.1397)
			(layers "F.Cu" "F.Mask" "F.Paste")
			(net "P3V3_EN")
			(options
				(clearance outline)
				(anchor circle)
			)
			(primitives
				(gr_poly
					(pts
						(arc
							(start -0.1778 -0.2794)
							(mid -0.249642 -0.249642)
							(end -0.2794 -0.1778)
						)
						(arc
							(start -0.2794 0.1778)
							(mid -0.249642 0.249642)
							(end -0.1778 0.2794)
						)
						(arc
							(start 0.1778 0.2794)
							(mid 0.249642 0.249642)
							(end 0.2794 0.1778)
						)
						(arc
							(start 0.2794 -0.1778)
							(mid 0.249642 -0.249642)
							(end 0.1778 -0.2794)
						)
					)
					(width 0)
					(fill yes)
				)
			)
		)
	)
)
